(kicad_pcb
	(version 20260206)
	(generator "pcbnew")
	(generator_version "10.0")
	(general
		(thickness 1.6)
		(legacy_teardrops no)
	)
	(paper "A4")
	(title_block
		(title "01162023_DA0F0TEBIF0_F0T_Expander_BD_F_brd_V02_OCP.brd")
		(comment 1 "Grand Teton / footprints 1729-1734 of 9728")
	)
	(layers
		(0 "F.Cu" signal "TOP")
		(4 "In1.Cu" signal "GND")
		(6 "In2.Cu" signal "VCC")
		(8 "In3.Cu" signal "VCC1")
		(10 "In4.Cu" signal "GND1")
		(12 "In5.Cu" signal "IN1")
		(14 "In6.Cu" signal "GND2")
		(16 "In7.Cu" signal "IN2")
		(18 "In8.Cu" signal "GND3")
		(20 "In9.Cu" signal "IN3")
		(22 "In10.Cu" signal "GND4")
		(24 "In11.Cu" signal "IN4")
		(26 "In12.Cu" signal "GND5")
		(28 "In13.Cu" signal "IN5")
		(30 "In14.Cu" signal "GND6")
		(32 "In15.Cu" signal "IN6")
		(34 "In16.Cu" signal "GND7")
		(2 "B.Cu" signal "BOTTOM")
		(9 "F.Adhes" user "F.Adhesive")
		(11 "B.Adhes" user "B.Adhesive")
		(13 "F.Paste" user "Package Geometry/Pastemask Top")
		(15 "B.Paste" user "Package Geometry/Pastemask Bottom")
		(5 "F.SilkS" user "Ref Des/Silkscreen Top")
		(7 "B.SilkS" user "Ref Des/Silkscreen Bottom")
		(1 "F.Mask" user "Board Geometry/Soldermask Top")
		(3 "B.Mask" user "Board Geometry/Soldermask Bottom")
		(17 "Dwgs.User" user "User.Drawings")
		(19 "Cmts.User" user "User.Comments")
		(21 "Eco1.User" user "User.Eco1")
		(23 "Eco2.User" user "User.Eco2")
		(25 "Edge.Cuts" user "Board Geometry/Outline")
		(27 "Margin" user)
		(31 "F.CrtYd" user "Package Geometry/Place Bound Top")
		(29 "B.CrtYd" user "Package Geometry/Place Bound Bottom")
		(35 "F.Fab" user "Ref Des/Assembly Top")
		(33 "B.Fab" user "Ref Des/Assembly Bottom")
	)
	(footprint ""
		(layer "F.Cu")
		(at 318.929512 -300.62043 90)
		(property "Reference" "R6394"
			(at 0 0 90)
			(layer "F.SilkS")
			(hide yes)
			(effects
				(font
					(size 1.27 1.27)
				)
			)
		)
		(property "Value" ""
			(at 0 0 90)
			(layer "F.Fab")
			(effects
				(font
					(size 1.27 1.27)
				)
			)
		)
		(duplicate_pad_numbers_are_jumpers no)
		(fp_line
			(start 0.7874 -0.4064)
			(end 0.7874 0.4064)
			(stroke
				(width 0.1524)
				(type default)
			)
			(layer "F.SilkS")
		)
		(fp_line
			(start -0.7874 -0.4064)
			(end 0.7874 -0.4064)
			(stroke
				(width 0.1524)
				(type default)
			)
			(layer "F.SilkS")
		)
		(fp_line
			(start 0.7874 0.4064)
			(end -0.7874 0.4064)
			(stroke
				(width 0.1524)
				(type default)
			)
			(layer "F.SilkS")
		)
		(fp_line
			(start -0.7874 0.4064)
			(end -0.7874 -0.4064)
			(stroke
				(width 0.1524)
				(type default)
			)
			(layer "F.SilkS")
		)
		(fp_line
			(start -0.12065 -0.305054)
			(end -0.12065 -0.2794)
			(stroke
				(width 0.1)
				(type default)
			)
			(layer "F.Fab")
		)
		(fp_line
			(start -0.67945 -0.305054)
			(end -0.12065 -0.305054)
			(stroke
				(width 0.1)
				(type default)
			)
			(layer "F.Fab")
		)
		(fp_line
			(start 0.67945 -0.3048)
			(end 0.67945 0.3048)
			(stroke
				(width 0.1)
				(type default)
			)
			(layer "F.Fab")
		)
		(fp_line
			(start 0.12065 -0.3048)
			(end 0.67945 -0.3048)
			(stroke
				(width 0.1)
				(type default)
			)
			(layer "F.Fab")
		)
		(fp_line
			(start 0.12065 -0.2794)
			(end 0.12065 -0.3048)
			(stroke
				(width 0.1)
				(type default)
			)
			(layer "F.Fab")
		)
		(fp_line
			(start -0.12065 -0.2794)
			(end 0.12065 -0.2794)
			(stroke
				(width 0.1)
				(type default)
			)
			(layer "F.Fab")
		)
		(fp_line
			(start 0.120396 0.2794)
			(end -0.12065 0.2794)
			(stroke
				(width 0.1)
				(type default)
			)
			(layer "F.Fab")
		)
		(fp_line
			(start -0.12065 0.2794)
			(end -0.12065 0.3048)
			(stroke
				(width 0.1)
				(type default)
			)
			(layer "F.Fab")
		)
		(fp_line
			(start 0.67945 0.3048)
			(end 0.120396 0.3048)
			(stroke
				(width 0.1)
				(type default)
			)
			(layer "F.Fab")
		)
		(fp_line
			(start 0.120396 0.3048)
			(end 0.120396 0.2794)
			(stroke
				(width 0.1)
				(type default)
			)
			(layer "F.Fab")
		)
		(fp_line
			(start -0.12065 0.3048)
			(end -0.67945 0.3048)
			(stroke
				(width 0.1)
				(type default)
			)
			(layer "F.Fab")
		)
		(fp_line
			(start -0.67945 0.3048)
			(end -0.67945 -0.305054)
			(stroke
				(width 0.1)
				(type default)
			)
			(layer "F.Fab")
		)
		(pad "1" smd circle
			(at -0.40005 0 90)
			(size 0 0)
			(layers "F.Cu" "F.Mask" "F.Paste")
			(net "RST_PEX2_S3_PERST_N")
		)
		(pad "2" smd circle
			(at 0.40005 0 90)
			(size 0 0)
			(layers "F.Cu" "F.Mask" "F.Paste")
			(net "RST_PEX2_S3_PERST_R_N")
		)
	)
	(footprint ""
		(layer "F.Cu")
		(at 280.790396 -414.88995 -90)
		(property "Reference" "R1815"
			(at 0 0 270)
			(layer "F.SilkS")
			(hide yes)
			(effects
				(font
					(size 1.27 1.27)
				)
			)
		)
		(property "Value" ""
			(at 0 0 270)
			(layer "F.Fab")
			(effects
				(font
					(size 1.27 1.27)
				)
			)
		)
		(duplicate_pad_numbers_are_jumpers no)
		(fp_line
			(start -0.7874 0.4064)
			(end -0.7874 -0.4064)
			(stroke
				(width 0.1524)
				(type default)
			)
			(layer "F.SilkS")
		)
		(fp_line
			(start 0.7874 0.4064)
			(end -0.7874 0.4064)
			(stroke
				(width 0.1524)
				(type default)
			)
			(layer "F.SilkS")
		)
		(fp_line
			(start -0.7874 -0.4064)
			(end 0.7874 -0.4064)
			(stroke
				(width 0.1524)
				(type default)
			)
			(layer "F.SilkS")
		)
		(fp_line
			(start 0.7874 -0.4064)
			(end 0.7874 0.4064)
			(stroke
				(width 0.1524)
				(type default)
			)
			(layer "F.SilkS")
		)
		(fp_line
			(start -0.67945 0.3048)
			(end -0.67945 -0.305054)
			(stroke
				(width 0.1)
				(type default)
			)
			(layer "F.Fab")
		)
		(fp_line
			(start -0.12065 0.3048)
			(end -0.67945 0.3048)
			(stroke
				(width 0.1)
				(type default)
			)
			(layer "F.Fab")
		)
		(fp_line
			(start 0.120396 0.3048)
			(end 0.120396 0.2794)
			(stroke
				(width 0.1)
				(type default)
			)
			(layer "F.Fab")
		)
		(fp_line
			(start 0.67945 0.3048)
			(end 0.120396 0.3048)
			(stroke
				(width 0.1)
				(type default)
			)
			(layer "F.Fab")
		)
		(fp_line
			(start -0.12065 0.2794)
			(end -0.12065 0.3048)
			(stroke
				(width 0.1)
				(type default)
			)
			(layer "F.Fab")
		)
		(fp_line
			(start 0.120396 0.2794)
			(end -0.12065 0.2794)
			(stroke
				(width 0.1)
				(type default)
			)
			(layer "F.Fab")
		)
		(fp_line
			(start -0.12065 -0.2794)
			(end 0.12065 -0.2794)
			(stroke
				(width 0.1)
				(type default)
			)
			(layer "F.Fab")
		)
		(fp_line
			(start 0.12065 -0.2794)
			(end 0.12065 -0.3048)
			(stroke
				(width 0.1)
				(type default)
			)
			(layer "F.Fab")
		)
		(fp_line
			(start 0.12065 -0.3048)
			(end 0.67945 -0.3048)
			(stroke
				(width 0.1)
				(type default)
			)
			(layer "F.Fab")
		)
		(fp_line
			(start 0.67945 -0.3048)
			(end 0.67945 0.3048)
			(stroke
				(width 0.1)
				(type default)
			)
			(layer "F.Fab")
		)
		(fp_line
			(start -0.67945 -0.305054)
			(end -0.12065 -0.305054)
			(stroke
				(width 0.1)
				(type default)
			)
			(layer "F.Fab")
		)
		(fp_line
			(start -0.12065 -0.305054)
			(end -0.12065 -0.2794)
			(stroke
				(width 0.1)
				(type default)
			)
			(layer "F.Fab")
		)
		(pad "1" smd circle
			(at -0.40005 0 270)
			(size 0 0)
			(layers "F.Cu" "F.Mask" "F.Paste")
			(net "MB_BIC_MON")
		)
		(pad "2" smd circle
			(at 0.40005 0 270)
			(size 0 0)
			(layers "F.Cu" "F.Mask" "F.Paste")
			(net "MB_BIC_R_MON")
		)
	)
	(footprint ""
		(layer "F.Cu")
		(at 313.784234 -457.938886 -90)
		(property "Reference" "J50"
			(at -2.4257 -5.635752 90)
			(unlocked yes)
			(layer "F.SilkS")
			(effects
				(font
					(size 0.7874 0.5842)
					(thickness 0.1524)
				)
			)
		)
		(property "Value" ""
			(at 0 0 270)
			(layer "F.Fab")
			(effects
				(font
					(size 1.27 1.27)
				)
			)
		)
		(duplicate_pad_numbers_are_jumpers no)
		(fp_line
			(start 0 4.011168)
			(end -3.330702 -4.771136)
			(stroke
				(width 0.1524)
				(type default)
			)
			(layer "F.SilkS")
		)
		(fp_line
			(start -3.330702 -4.771136)
			(end 3.330702 -4.771136)
			(stroke
				(width 0.1524)
				(type default)
			)
			(layer "F.SilkS")
		)
		(fp_line
			(start 3.330702 -4.771136)
			(end 0 4.011168)
			(stroke
				(width 0.1524)
				(type default)
			)
			(layer "F.SilkS")
		)
		(fp_line
			(start 0 4.011168)
			(end -3.330702 -4.771136)
			(stroke
				(width 0.1)
				(type default)
			)
			(layer "F.Fab")
		)
		(fp_line
			(start -3.330702 -4.771136)
			(end 3.330702 -4.771136)
			(stroke
				(width 0.1)
				(type default)
			)
			(layer "F.Fab")
		)
		(fp_line
			(start 3.330702 -4.771136)
			(end 0 4.011168)
			(stroke
				(width 0.1)
				(type default)
			)
			(layer "F.Fab")
		)
		(pad "1" thru_hole circle
			(at 0 0 270)
			(size 2.159 2.159)
			(drill 1.7018)
			(layers "*.Cu" "*.Mask")
			(remove_unused_layers no)
			(net "COUPON_GND1")
			(clearance 0.0254)
			(thermal_gap 0.0254)
		)
		(pad "2" thru_hole circle
			(at -1.27 -3.348736 270)
			(size 2.159 2.159)
			(drill 1.7018)
			(layers "*.Cu" "*.Mask")
			(remove_unused_layers no)
			(net "TDR_SE_50_OHM_IN4")
			(clearance 0.0254)
			(thermal_gap 0.0254)
		)
		(pad "3" thru_hole circle
			(at 1.27 -3.348736 270)
			(size 2.159 2.159)
			(drill 1.7018)
			(layers "*.Cu" "*.Mask")
			(remove_unused_layers no)
			(net "TDR_SE_50_OHM_IN4")
			(clearance 0.0254)
			(thermal_gap 0.0254)
		)
	)
	(footprint ""
		(layer "F.Cu")
		(at 336.443574 -42.84091)
		(property "Reference" "R627"
			(at 0 0 0)
			(layer "F.SilkS")
			(hide yes)
			(effects
				(font
					(size 1.27 1.27)
				)
			)
		)
		(property "Value" ""
			(at 0 0 0)
			(layer "F.Fab")
			(effects
				(font
					(size 1.27 1.27)
				)
			)
		)
		(duplicate_pad_numbers_are_jumpers no)
		(fp_line
			(start -0.7874 -0.4064)
			(end 0.7874 -0.4064)
			(stroke
				(width 0.1524)
				(type default)
			)
			(layer "F.SilkS")
		)
		(fp_line
			(start -0.7874 0.4064)
			(end -0.7874 -0.4064)
			(stroke
				(width 0.1524)
				(type default)
			)
			(layer "F.SilkS")
		)
		(fp_line
			(start 0.7874 -0.4064)
			(end 0.7874 0.4064)
			(stroke
				(width 0.1524)
				(type default)
			)
			(layer "F.SilkS")
		)
		(fp_line
			(start 0.7874 0.4064)
			(end -0.7874 0.4064)
			(stroke
				(width 0.1524)
				(type default)
			)
			(layer "F.SilkS")
		)
		(fp_line
			(start -0.67945 -0.305054)
			(end -0.12065 -0.305054)
			(stroke
				(width 0.1)
				(type default)
			)
			(layer "F.Fab")
		)
		(fp_line
			(start -0.67945 0.3048)
			(end -0.67945 -0.305054)
			(stroke
				(width 0.1)
				(type default)
			)
			(layer "F.Fab")
		)
		(fp_line
			(start -0.12065 -0.305054)
			(end -0.12065 -0.2794)
			(stroke
				(width 0.1)
				(type default)
			)
			(layer "F.Fab")
		)
		(fp_line
			(start -0.12065 -0.2794)
			(end 0.12065 -0.2794)
			(stroke
				(width 0.1)
				(type default)
			)
			(layer "F.Fab")
		)
		(fp_line
			(start -0.12065 0.2794)
			(end -0.12065 0.3048)
			(stroke
				(width 0.1)
				(type default)
			)
			(layer "F.Fab")
		)
		(fp_line
			(start -0.12065 0.3048)
			(end -0.67945 0.3048)
			(stroke
				(width 0.1)
				(type default)
			)
			(layer "F.Fab")
		)
		(fp_line
			(start 0.120396 0.2794)
			(end -0.12065 0.2794)
			(stroke
				(width 0.1)
				(type default)
			)
			(layer "F.Fab")
		)
		(fp_line
			(start 0.120396 0.3048)
			(end 0.120396 0.2794)
			(stroke
				(width 0.1)
				(type default)
			)
			(layer "F.Fab")
		)
		(fp_line
			(start 0.12065 -0.3048)
			(end 0.67945 -0.3048)
			(stroke
				(width 0.1)
				(type default)
			)
			(layer "F.Fab")
		)
		(fp_line
			(start 0.12065 -0.2794)
			(end 0.12065 -0.3048)
			(stroke
				(width 0.1)
				(type default)
			)
			(layer "F.Fab")
		)
		(fp_line
			(start 0.67945 -0.3048)
			(end 0.67945 0.3048)
			(stroke
				(width 0.1)
				(type default)
			)
			(layer "F.Fab")
		)
		(fp_line
			(start 0.67945 0.3048)
			(end 0.120396 0.3048)
			(stroke
				(width 0.1)
				(type default)
			)
			(layer "F.Fab")
		)
		(pad "1" smd circle
			(at -0.40005 0)
			(size 0 0)
			(layers "F.Cu" "F.Mask" "F.Paste")
			(net "SSD11_ADC_A1")
		)
		(pad "2" smd circle
			(at 0.40005 0)
			(size 0 0)
			(layers "F.Cu" "F.Mask" "F.Paste")
			(net "P3V3_AUX")
		)
	)
	(footprint ""
		(layer "F.Cu")
		(at 345.694 -205.232 90)
		(property "Reference" "R4144"
			(at 0 0 90)
			(layer "F.SilkS")
			(hide yes)
			(effects
				(font
					(size 1.27 1.27)
				)
			)
		)
		(property "Value" ""
			(at 0 0 90)
			(layer "F.Fab")
			(effects
				(font
					(size 1.27 1.27)
				)
			)
		)
		(duplicate_pad_numbers_are_jumpers no)
		(fp_line
			(start 0.7874 -0.4064)
			(end 0.7874 0.4064)
			(stroke
				(width 0.1524)
				(type default)
			)
			(layer "F.SilkS")
		)
		(fp_line
			(start -0.7874 -0.4064)
			(end 0.7874 -0.4064)
			(stroke
				(width 0.1524)
				(type default)
			)
			(layer "F.SilkS")
		)
		(fp_line
			(start 0.7874 0.4064)
			(end -0.7874 0.4064)
			(stroke
				(width 0.1524)
				(type default)
			)
			(layer "F.SilkS")
		)
		(fp_line
			(start -0.7874 0.4064)
			(end -0.7874 -0.4064)
			(stroke
				(width 0.1524)
				(type default)
			)
			(layer "F.SilkS")
		)
		(fp_line
			(start -0.12065 -0.305054)
			(end -0.12065 -0.2794)
			(stroke
				(width 0.1)
				(type default)
			)
			(layer "F.Fab")
		)
		(fp_line
			(start -0.67945 -0.305054)
			(end -0.12065 -0.305054)
			(stroke
				(width 0.1)
				(type default)
			)
			(layer "F.Fab")
		)
		(fp_line
			(start 0.67945 -0.3048)
			(end 0.67945 0.3048)
			(stroke
				(width 0.1)
				(type default)
			)
			(layer "F.Fab")
		)
		(fp_line
			(start 0.12065 -0.3048)
			(end 0.67945 -0.3048)
			(stroke
				(width 0.1)
				(type default)
			)
			(layer "F.Fab")
		)
		(fp_line
			(start 0.12065 -0.2794)
			(end 0.12065 -0.3048)
			(stroke
				(width 0.1)
				(type default)
			)
			(layer "F.Fab")
		)
		(fp_line
			(start -0.12065 -0.2794)
			(end 0.12065 -0.2794)
			(stroke
				(width 0.1)
				(type default)
			)
			(layer "F.Fab")
		)
		(fp_line
			(start 0.120396 0.2794)
			(end -0.12065 0.2794)
			(stroke
				(width 0.1)
				(type default)
			)
			(layer "F.Fab")
		)
		(fp_line
			(start -0.12065 0.2794)
			(end -0.12065 0.3048)
			(stroke
				(width 0.1)
				(type default)
			)
			(layer "F.Fab")
		)
		(fp_line
			(start 0.67945 0.3048)
			(end 0.120396 0.3048)
			(stroke
				(width 0.1)
				(type default)
			)
			(layer "F.Fab")
		)
		(fp_line
			(start 0.120396 0.3048)
			(end 0.120396 0.2794)
			(stroke
				(width 0.1)
				(type default)
			)
			(layer "F.Fab")
		)
		(fp_line
			(start -0.12065 0.3048)
			(end -0.67945 0.3048)
			(stroke
				(width 0.1)
				(type default)
			)
			(layer "F.Fab")
		)
		(fp_line
			(start -0.67945 0.3048)
			(end -0.67945 -0.305054)
			(stroke
				(width 0.1)
				(type default)
			)
			(layer "F.Fab")
		)
		(pad "1" smd circle
			(at -0.40005 0 90)
			(size 0 0)
			(layers "F.Cu" "F.Mask" "F.Paste")
			(net "SSD15_PWRDIS_R")
		)
		(pad "2" smd circle
			(at 0.40005 0 90)
			(size 0 0)
			(layers "F.Cu" "F.Mask" "F.Paste")
			(net "SSD15_PWRDIS")
		)
	)
	(footprint ""
		(layer "F.Cu")
		(at 60.389262 -390.07161 90)
		(property "Reference" "R6256"
			(at 0 0 90)
			(layer "F.SilkS")
			(hide yes)
			(effects
				(font
					(size 1.27 1.27)
				)
			)
		)
		(property "Value" ""
			(at 0 0 90)
			(layer "F.Fab")
			(effects
				(font
					(size 1.27 1.27)
				)
			)
		)
		(duplicate_pad_numbers_are_jumpers no)
		(fp_line
			(start 0.7874 -0.4064)
			(end 0.7874 0.4064)
			(stroke
				(width 0.1524)
				(type default)
			)
			(layer "F.SilkS")
		)
		(fp_line
			(start -0.7874 -0.4064)
			(end 0.7874 -0.4064)
			(stroke
				(width 0.1524)
				(type default)
			)
			(layer "F.SilkS")
		)
		(fp_line
			(start 0.7874 0.4064)
			(end -0.7874 0.4064)
			(stroke
				(width 0.1524)
				(type default)
			)
			(layer "F.SilkS")
		)
		(fp_line
			(start -0.7874 0.4064)
			(end -0.7874 -0.4064)
			(stroke
				(width 0.1524)
				(type default)
			)
			(layer "F.SilkS")
		)
		(fp_line
			(start -0.12065 -0.305054)
			(end -0.12065 -0.2794)
			(stroke
				(width 0.1)
				(type default)
			)
			(layer "F.Fab")
		)
		(fp_line
			(start -0.67945 -0.305054)
			(end -0.12065 -0.305054)
			(stroke
				(width 0.1)
				(type default)
			)
			(layer "F.Fab")
		)
		(fp_line
			(start 0.67945 -0.3048)
			(end 0.67945 0.3048)
			(stroke
				(width 0.1)
				(type default)
			)
			(layer "F.Fab")
		)
		(fp_line
			(start 0.12065 -0.3048)
			(end 0.67945 -0.3048)
			(stroke
				(width 0.1)
				(type default)
			)
			(layer "F.Fab")
		)
		(fp_line
			(start 0.12065 -0.2794)
			(end 0.12065 -0.3048)
			(stroke
				(width 0.1)
				(type default)
			)
			(layer "F.Fab")
		)
		(fp_line
			(start -0.12065 -0.2794)
			(end 0.12065 -0.2794)
			(stroke
				(width 0.1)
				(type default)
			)
			(layer "F.Fab")
		)
		(fp_line
			(start 0.120396 0.2794)
			(end -0.12065 0.2794)
			(stroke
				(width 0.1)
				(type default)
			)
			(layer "F.Fab")
		)
		(fp_line
			(start -0.12065 0.2794)
			(end -0.12065 0.3048)
			(stroke
				(width 0.1)
				(type default)
			)
			(layer "F.Fab")
		)
		(fp_line
			(start 0.67945 0.3048)
			(end 0.120396 0.3048)
			(stroke
				(width 0.1)
				(type default)
			)
			(layer "F.Fab")
		)
		(fp_line
			(start 0.120396 0.3048)
			(end 0.120396 0.2794)
			(stroke
				(width 0.1)
				(type default)
			)
			(layer "F.Fab")
		)
		(fp_line
			(start -0.12065 0.3048)
			(end -0.67945 0.3048)
			(stroke
				(width 0.1)
				(type default)
			)
			(layer "F.Fab")
		)
		(fp_line
			(start -0.67945 0.3048)
			(end -0.67945 -0.305054)
			(stroke
				(width 0.1)
				(type default)
			)
			(layer "F.Fab")
		)
		(pad "1" smd circle
			(at -0.40005 0 90)
			(size 0 0)
			(layers "F.Cu" "F.Mask" "F.Paste")
			(net "GPU_HGX_DETECT_R_N")
		)
		(pad "2" smd circle
			(at 0.40005 0 90)
			(size 0 0)
			(layers "F.Cu" "F.Mask" "F.Paste")
			(net "GPU_HGX_DETECT_N")
		)
	)
)
